(kicad_pcb
	(version 20260206)
	(generator "pcbnew")
	(generator_version "10.0")
	(general
		(thickness 1.6)
		(legacy_teardrops no)
	)
	(paper "A4")
	(title_block
		(title "Bryce Canyon_F.DPB_16315-1-OCP.brd")
		(comment 1 "Bryce Canyon / footprints 354-361 of 2223")
	)
	(layers
		(0 "F.Cu" signal "TOP")
		(4 "In1.Cu" signal "L2GND")
		(6 "In2.Cu" signal "L3")
		(8 "In3.Cu" signal "L4GND")
		(10 "In4.Cu" signal "L5")
		(12 "In5.Cu" signal "L6VCC")
		(14 "In6.Cu" signal "L7VCC")
		(16 "In7.Cu" signal "L8")
		(18 "In8.Cu" signal "L9GND")
		(20 "In9.Cu" signal "L10")
		(22 "In10.Cu" signal "L11GND")
		(2 "B.Cu" signal "BOTTOM")
		(9 "F.Adhes" user "F.Adhesive")
		(11 "B.Adhes" user "B.Adhesive")
		(13 "F.Paste" user "Package Geometry/Pastemask Top")
		(15 "B.Paste" user "Package Geometry/Pastemask Bottom")
		(5 "F.SilkS" user "Ref Des/Silkscreen Top")
		(7 "B.SilkS" user "Ref Des/Silkscreen Bottom")
		(1 "F.Mask" user "Board Geometry/Soldermask Top")
		(3 "B.Mask" user "Board Geometry/Soldermask Bottom")
		(17 "Dwgs.User" user "User.Drawings")
		(19 "Cmts.User" user "User.Comments")
		(21 "Eco1.User" user "User.Eco1")
		(23 "Eco2.User" user "User.Eco2")
		(25 "Edge.Cuts" user "Board Geometry/Outline")
		(27 "Margin" user)
		(31 "F.CrtYd" user "Package Geometry/Place Bound Top")
		(29 "B.CrtYd" user "Package Geometry/Place Bound Bottom")
		(35 "F.Fab" user "Ref Des/Assembly Top")
		(33 "B.Fab" user "Ref Des/Assembly Bottom")
	)
	(footprint ""
		(layer "F.Cu")
		(at 401.80895 -56.809894 -90)
		(property "Reference" "R880"
			(at 0 0 270)
			(layer "F.SilkS")
			(hide yes)
			(effects
				(font
					(size 1.27 1.27)
				)
			)
		)
		(property "Value" "300KR2F-GP"
			(at 0.064008 -3.993896 270)
			(unlocked yes)
			(layer "F.Fab")
			(hide yes)
			(effects
				(font
					(size 1.016 1.016)
					(thickness 0.1524)
				)
			)
		)
		(property "Device Type" "R402H16"
			(at 0.064008 -5.517896 270)
			(unlocked yes)
			(layer "F.Fab")
			(hide yes)
			(effects
				(font
					(size 1.016 1.016)
					(thickness 0.1524)
				)
			)
		)
		(duplicate_pad_numbers_are_jumpers no)
		(fp_line
			(start -0.508 -0.9398)
			(end -0.508 0.9398)
			(stroke
				(width 0.1524)
				(type default)
			)
			(layer "F.SilkS")
		)
		(fp_line
			(start 0.508 -0.9398)
			(end -0.508 -0.9398)
			(stroke
				(width 0.1524)
				(type default)
			)
			(layer "F.SilkS")
		)
		(fp_rect
			(start -0.508 0.9398)
			(end 0.508 -0.9398)
			(stroke
				(width 0)
				(type default)
			)
			(fill no)
			(layer "F.CrtYd")
		)
		(fp_rect
			(start -0.508 0.9398)
			(end 0.508 -0.9398)
			(stroke
				(width 0)
				(type default)
			)
			(fill no)
			(layer "F.Fab")
		)
		(pad "1" smd custom
			(at 0 -0.4445 270)
			(size 0.1397 0.1397)
			(layers "F.Cu" "F.Mask" "F.Paste")
			(net "SW_HDD_N32")
			(options
				(clearance outline)
				(anchor circle)
			)
			(primitives
				(gr_poly
					(pts
						(arc
							(start -0.1778 -0.2794)
							(mid -0.249642 -0.249642)
							(end -0.2794 -0.1778)
						)
						(arc
							(start -0.2794 0.1778)
							(mid -0.249642 0.249642)
							(end -0.1778 0.2794)
						)
						(arc
							(start 0.1778 0.2794)
							(mid 0.249642 0.249642)
							(end 0.2794 0.1778)
						)
						(arc
							(start 0.2794 -0.1778)
							(mid 0.249642 -0.249642)
							(end 0.1778 -0.2794)
						)
					)
					(width 0)
					(fill yes)
				)
			)
		)
		(pad "2" smd custom
			(at 0 0.4445 270)
			(size 0.1397 0.1397)
			(layers "F.Cu" "F.Mask" "F.Paste")
			(net "P12V_A")
			(options
				(clearance outline)
				(anchor circle)
			)
			(primitives
				(gr_poly
					(pts
						(arc
							(start -0.1778 -0.2794)
							(mid -0.249642 -0.249642)
							(end -0.2794 -0.1778)
						)
						(arc
							(start -0.2794 0.1778)
							(mid -0.249642 0.249642)
							(end -0.1778 0.2794)
						)
						(arc
							(start 0.1778 0.2794)
							(mid 0.249642 0.249642)
							(end 0.2794 0.1778)
						)
						(arc
							(start 0.2794 -0.1778)
							(mid 0.249642 -0.249642)
							(end 0.1778 -0.2794)
						)
					)
					(width 0)
					(fill yes)
				)
			)
		)
	)
	(footprint ""
		(layer "F.Cu")
		(at 236.024928 -234.6071 180)
		(property "Reference" "C22"
			(at 0 0 180)
			(layer "F.SilkS")
			(hide yes)
			(effects
				(font
					(size 1.27 1.27)
				)
			)
		)
		(property "Value" "SCD1U16V2KX-3GP"
			(at 1.1811 -2.7051 180)
			(unlocked yes)
			(layer "F.Fab")
			(hide yes)
			(effects
				(font
					(size 1.016 1.016)
					(thickness 0.1524)
				)
			)
		)
		(property "Device Type" "C402H22"
			(at 1.1811 -4.2291 180)
			(unlocked yes)
			(layer "F.Fab")
			(hide yes)
			(effects
				(font
					(size 1.016 1.016)
					(thickness 0.1524)
				)
			)
		)
		(duplicate_pad_numbers_are_jumpers no)
		(fp_rect
			(start -0.4318 0.9525)
			(end 0.4318 -0.9525)
			(stroke
				(width 0)
				(type default)
			)
			(fill no)
			(layer "F.CrtYd")
		)
		(fp_rect
			(start -0.4318 0.9525)
			(end 0.4318 -0.9525)
			(stroke
				(width 0)
				(type default)
			)
			(fill no)
			(layer "F.Fab")
		)
		(pad "1" smd custom
			(at 0 -0.4445 180)
			(size 0.1524 0.1524)
			(layers "F.Cu" "F.Mask" "F.Paste")
			(net "GPIO_VCC_U7")
			(options
				(clearance outline)
				(anchor circle)
			)
			(primitives
				(gr_poly
					(pts
						(arc
							(start 0.3048 -0.2032)
							(mid 0.275042 -0.275042)
							(end 0.2032 -0.3048)
						)
						(arc
							(start -0.2032 -0.3048)
							(mid -0.275042 -0.275042)
							(end -0.3048 -0.2032)
						)
						(arc
							(start -0.3048 0.2032)
							(mid -0.275042 0.275042)
							(end -0.2032 0.3048)
						)
						(arc
							(start 0.2032 0.3048)
							(mid 0.275042 0.275042)
							(end 0.3048 0.2032)
						)
					)
					(width 0)
					(fill yes)
				)
			)
		)
		(pad "2" smd custom
			(at 0 0.4445 180)
			(size 0.1524 0.1524)
			(layers "F.Cu" "F.Mask" "F.Paste")
			(net "GND")
			(options
				(clearance outline)
				(anchor circle)
			)
			(primitives
				(gr_poly
					(pts
						(arc
							(start 0.3048 -0.2032)
							(mid 0.275042 -0.275042)
							(end 0.2032 -0.3048)
						)
						(arc
							(start -0.2032 -0.3048)
							(mid -0.275042 -0.275042)
							(end -0.3048 -0.2032)
						)
						(arc
							(start -0.3048 0.2032)
							(mid -0.275042 0.275042)
							(end -0.2032 0.3048)
						)
						(arc
							(start 0.2032 0.3048)
							(mid 0.275042 0.275042)
							(end 0.3048 0.2032)
						)
					)
					(width 0)
					(fill yes)
				)
			)
		)
	)
	(footprint ""
		(layer "F.Cu")
		(at 333.502 -303.954942 180)
		(property "Reference" "C123"
			(at 0 0 180)
			(layer "F.SilkS")
			(hide yes)
			(effects
				(font
					(size 1.27 1.27)
				)
			)
		)
		(property "Value" "SC4D7U25V5KX-1-GP"
			(at -0.0762 -6.1214 180)
			(unlocked yes)
			(layer "F.Fab")
			(hide yes)
			(effects
				(font
					(size 1.016 1.016)
					(thickness 0.1524)
				)
			)
		)
		(property "Device Type" "C805H58"
			(at -0.0762 -8.1534 180)
			(unlocked yes)
			(layer "F.Fab")
			(hide yes)
			(effects
				(font
					(size 1.016 1.016)
					(thickness 0.1524)
				)
			)
		)
		(duplicate_pad_numbers_are_jumpers no)
		(fp_line
			(start 0.635 0)
			(end -0.635 0)
			(stroke
				(width 0.508)
				(type default)
			)
			(layer "F.SilkS")
		)
		(fp_rect
			(start -0.9652 1.778)
			(end 0.9652 -1.778)
			(stroke
				(width 0)
				(type default)
			)
			(fill no)
			(layer "F.CrtYd")
		)
		(fp_poly
			(pts
				(xy -0.9652 -1.778) (xy 0.9652 -1.778) (xy 0.9652 1.778) (xy -0.9652 1.778)
			)
			(stroke
				(width 0)
				(type default)
			)
			(fill no)
			(layer "F.Fab")
		)
		(pad "1" smd rect
			(at 0 -0.9652 180)
			(size 1.397 1.143)
			(layers "F.Cu" "F.Mask" "F.Paste")
			(net "P12V_HDD6")
		)
		(pad "2" smd rect
			(at 0 0.9652 180)
			(size 1.397 1.143)
			(layers "F.Cu" "F.Mask" "F.Paste")
			(net "GND")
		)
	)
	(footprint ""
		(layer "F.Cu")
		(at 459.7019 -303.954942 180)
		(property "Reference" "C175"
			(at 0 0 180)
			(layer "F.SilkS")
			(hide yes)
			(effects
				(font
					(size 1.27 1.27)
				)
			)
		)
		(property "Value" "SC4D7U25V5KX-1-GP"
			(at -0.0762 -6.1214 180)
			(unlocked yes)
			(layer "F.Fab")
			(hide yes)
			(effects
				(font
					(size 1.016 1.016)
					(thickness 0.1524)
				)
			)
		)
		(property "Device Type" "C805H58"
			(at -0.0762 -8.1534 180)
			(unlocked yes)
			(layer "F.Fab")
			(hide yes)
			(effects
				(font
					(size 1.016 1.016)
					(thickness 0.1524)
				)
			)
		)
		(duplicate_pad_numbers_are_jumpers no)
		(fp_line
			(start 0.635 0)
			(end -0.635 0)
			(stroke
				(width 0.508)
				(type default)
			)
			(layer "F.SilkS")
		)
		(fp_rect
			(start -0.9652 1.778)
			(end 0.9652 -1.778)
			(stroke
				(width 0)
				(type default)
			)
			(fill no)
			(layer "F.CrtYd")
		)
		(fp_poly
			(pts
				(xy -0.9652 -1.778) (xy 0.9652 -1.778) (xy 0.9652 1.778) (xy -0.9652 1.778)
			)
			(stroke
				(width 0)
				(type default)
			)
			(fill no)
			(layer "F.Fab")
		)
		(pad "1" smd rect
			(at 0 -0.9652 180)
			(size 1.397 1.143)
			(layers "F.Cu" "F.Mask" "F.Paste")
			(net "P12V_HDD10")
		)
		(pad "2" smd rect
			(at 0 0.9652 180)
			(size 1.397 1.143)
			(layers "F.Cu" "F.Mask" "F.Paste")
			(net "GND")
		)
	)
	(footprint ""
		(layer "F.Cu")
		(at 67.093846 -68.747894)
		(property "Reference" "TP127"
			(at 0 0 0)
			(layer "F.SilkS")
			(hide yes)
			(effects
				(font
					(size 1.27 1.27)
				)
			)
		)
		(property "Value" "TPAD32-GP"
			(at -0.0508 -1.6764 0)
			(unlocked yes)
			(layer "F.Fab")
			(hide yes)
			(effects
				(font
					(size 1.016 1.016)
					(thickness 0.1524)
				)
			)
		)
		(property "Device Type" "TPAD32"
			(at -0.0508 -3.2004 0)
			(unlocked yes)
			(layer "F.Fab")
			(hide yes)
			(effects
				(font
					(size 1.016 1.016)
					(thickness 0.1524)
				)
			)
		)
		(duplicate_pad_numbers_are_jumpers no)
		(fp_poly
			(pts
				(arc
					(start 0.4064 0)
					(mid -0.4064 0)
					(end 0.4064 0)
				)
			)
			(stroke
				(width 0)
				(type default)
			)
			(fill no)
			(layer "F.CrtYd")
		)
		(fp_poly
			(pts
				(arc
					(start 0.7112 0)
					(mid -0.7112 0)
					(end 0.7112 0)
				)
			)
			(stroke
				(width 0)
				(type default)
			)
			(fill no)
			(layer "F.Fab")
		)
		(pad "1" smd circle
			(at 0 0)
			(size 0.8128 0.8128)
			(layers "F.Cu" "F.Mask" "F.Paste")
			(net "ACT_HDD_25")
		)
	)
	(footprint ""
		(layer "F.Cu")
		(at 33.325054 -92.799916)
		(property "Reference" ""
			(at 0 0 0)
			(layer "F.SilkS")
			(hide yes)
			(effects
				(font
					(size 1.27 1.27)
				)
			)
		)
		(property "Value" "*"
			(at -8.398764 -8.057642 0)
			(unlocked yes)
			(layer "F.Fab")
			(hide yes)
			(effects
				(font
					(size 1.016 1.016)
					(thickness 0.1524)
				)
			)
		)
		(duplicate_pad_numbers_are_jumpers no)
		(fp_poly
			(pts
				(arc
					(start 7.3152 0)
					(mid 0 7.3152)
					(end -7.3152 0)
				)
				(arc
					(start -7.3152 -5.9944)
					(mid 0 -13.3096)
					(end 7.3152 -5.9944)
				)
			)
			(stroke
				(width 0)
				(type default)
			)
			(fill no)
			(layer "B.CrtYd")
		)
		(fp_poly
			(pts
				(arc
					(start 7.3152 0)
					(mid 0 7.3152)
					(end -7.3152 0)
				)
				(arc
					(start -7.3152 -5.9944)
					(mid 0 -13.3096)
					(end 7.3152 -5.9944)
				)
			)
			(stroke
				(width 0)
				(type default)
			)
			(fill no)
			(layer "F.CrtYd")
		)
		(fp_poly
			(pts
				(arc
					(start 7.3152 0)
					(mid 0 7.3152)
					(end -7.3152 0)
				)
				(arc
					(start -7.3152 -5.9944)
					(mid 0 -13.3096)
					(end 7.3152 -5.9944)
				)
			)
			(stroke
				(width 0)
				(type default)
			)
			(fill no)
			(layer "B.Fab")
		)
		(fp_poly
			(pts
				(arc
					(start 7.3152 0)
					(mid 0 7.3152)
					(end -7.3152 0)
				)
				(arc
					(start -7.3152 -5.9944)
					(mid 0 -13.3096)
					(end 7.3152 -5.9944)
				)
			)
			(stroke
				(width 0)
				(type default)
			)
			(fill no)
			(layer "F.Fab")
		)
		(pad "1" thru_hole oval
			(at 0 0)
			(size 14.0208 20.0152)
			(drill 0.0254
				(offset 0 -2.9972)
			)
			(layers "*.Cu" "*.Mask")
			(remove_unused_layers no)
			(net "Net_28")
			(clearance -1.002284)
			(thermal_gap 0.1524)
			(padstack
				(mode front_inner_back)
				(layer "Inner"
					(shape custom)
					(size 2.928012 2.928012)
					(options
						(anchor circle)
					)
					(primitives
						(gr_poly
							(pts
								(arc
									(start 4.571746 -2.084324)
									(mid 0.000333 7.430372)
									(end -4.571492 -2.084324)
								)
								(arc
									(start -4.571492 -2.084324)
									(mid -3.570296 -3.611977)
									(end -2.875026 -5.30098)
								)
								(arc
									(start -2.875026 -5.30098)
									(mid 0.000217 -7.43089)
									(end 2.87528 -5.30098)
								)
								(arc
									(start 2.87528 -5.30098)
									(mid 3.570511 -3.611956)
									(end 4.571746 -2.084324)
								)
							)
							(width 0)
							(fill yes)
						)
					)
					(clearance 0.1524)
				)
				(layer "B.Cu"
					(shape oval)
					(size 14.0208 20.0152)
					(offset 0 -2.9972)
					(clearance -1.002284)
				)
			)
		)
		(zone
			(layers "F.Cu" "B.Cu" "In1.Cu" "In2.Cu" "In3.Cu" "In4.Cu" "In5.Cu" "In6.Cu"
				"In7.Cu" "In8.Cu" "In9.Cu" "In10.Cu"
			)
			(hatch none 0.5)
			(connect_pads
				(clearance 0)
			)
			(min_thickness 0.25)
			(keepout
				(tracks not_allowed)
				(vias allowed)
				(pads allowed)
				(copperpour not_allowed)
				(footprints allowed)
			)
			(placement
				(enabled no)
				(sheetname "")
			)
			(fill
				(thermal_gap 0.5)
				(thermal_bridge_width 0.5)
				(island_removal_mode 0)
			)
			(polygon
				(pts
					(arc
						(start 26.314654 -98.794316)
						(mid 33.325054 -105.804716)
						(end 40.335454 -98.794316)
					)
					(arc
						(start 40.335454 -92.799916)
						(mid 33.325054 -85.789516)
						(end 26.314654 -92.799916)
					)
				)
			)
		)
	)
	(footprint ""
		(layer "F.Cu")
		(at 42.992802 -145.72615 -90)
		(property "Reference" "R1238"
			(at 0 0 270)
			(layer "F.SilkS")
			(hide yes)
			(effects
				(font
					(size 1.27 1.27)
				)
			)
		)
		(property "Value" "309KR2F-GP"
			(at 0.064008 -3.993896 270)
			(unlocked yes)
			(layer "F.Fab")
			(hide yes)
			(effects
				(font
					(size 1.016 1.016)
					(thickness 0.1524)
				)
			)
		)
		(property "Device Type" "R402H16"
			(at 0.064008 -5.517896 270)
			(unlocked yes)
			(layer "F.Fab")
			(hide yes)
			(effects
				(font
					(size 1.016 1.016)
					(thickness 0.1524)
				)
			)
		)
		(duplicate_pad_numbers_are_jumpers no)
		(fp_line
			(start -0.508 -0.9398)
			(end -0.508 0.9398)
			(stroke
				(width 0.1524)
				(type default)
			)
			(layer "F.SilkS")
		)
		(fp_line
			(start 0.508 -0.9398)
			(end -0.508 -0.9398)
			(stroke
				(width 0.1524)
				(type default)
			)
			(layer "F.SilkS")
		)
		(fp_rect
			(start -0.508 0.9398)
			(end 0.508 -0.9398)
			(stroke
				(width 0)
				(type default)
			)
			(fill no)
			(layer "F.CrtYd")
		)
		(fp_rect
			(start -0.508 0.9398)
			(end 0.508 -0.9398)
			(stroke
				(width 0)
				(type default)
			)
			(fill no)
			(layer "F.Fab")
		)
		(pad "1" smd custom
			(at 0 -0.4445 270)
			(size 0.1397 0.1397)
			(layers "F.Cu" "F.Mask" "F.Paste")
			(net "P5V_B_RF")
			(options
				(clearance outline)
				(anchor circle)
			)
			(primitives
				(gr_poly
					(pts
						(arc
							(start -0.1778 -0.2794)
							(mid -0.249642 -0.249642)
							(end -0.2794 -0.1778)
						)
						(arc
							(start -0.2794 0.1778)
							(mid -0.249642 0.249642)
							(end -0.1778 0.2794)
						)
						(arc
							(start 0.1778 0.2794)
							(mid 0.249642 0.249642)
							(end 0.2794 0.1778)
						)
						(arc
							(start 0.2794 -0.1778)
							(mid 0.249642 -0.249642)
							(end 0.1778 -0.2794)
						)
					)
					(width 0)
					(fill yes)
				)
			)
		)
		(pad "2" smd custom
			(at 0 0.4445 270)
			(size 0.1397 0.1397)
			(layers "F.Cu" "F.Mask" "F.Paste")
			(net "P5V_B_VREG")
			(options
				(clearance outline)
				(anchor circle)
			)
			(primitives
				(gr_poly
					(pts
						(arc
							(start -0.1778 -0.2794)
							(mid -0.249642 -0.249642)
							(end -0.2794 -0.1778)
						)
						(arc
							(start -0.2794 0.1778)
							(mid -0.249642 0.249642)
							(end -0.1778 0.2794)
						)
						(arc
							(start 0.1778 0.2794)
							(mid 0.249642 0.249642)
							(end 0.2794 0.1778)
						)
						(arc
							(start 0.2794 -0.1778)
							(mid 0.249642 -0.249642)
							(end 0.1778 -0.2794)
						)
					)
					(width 0)
					(fill yes)
				)
			)
		)
	)
	(footprint ""
		(layer "F.Cu")
		(at 478.282 -163.068)
		(property "Reference" "C345"
			(at 0 0 0)
			(layer "F.SilkS")
			(hide yes)
			(effects
				(font
					(size 1.27 1.27)
				)
			)
		)
		(property "Value" "SCD01U50V2KX-1GP"
			(at 1.1811 -2.7051 0)
			(unlocked yes)
			(layer "F.Fab")
			(hide yes)
			(effects
				(font
					(size 1.016 1.016)
					(thickness 0.1524)
				)
			)
		)
		(property "Device Type" "C402H22"
			(at 1.1811 -4.2291 0)
			(unlocked yes)
			(layer "F.Fab")
			(hide yes)
			(effects
				(font
					(size 1.016 1.016)
					(thickness 0.1524)
				)
			)
		)
		(duplicate_pad_numbers_are_jumpers no)
		(fp_rect
			(start -0.4318 0.9525)
			(end 0.4318 -0.9525)
			(stroke
				(width 0)
				(type default)
			)
			(fill no)
			(layer "F.CrtYd")
		)
		(fp_rect
			(start -0.4318 0.9525)
			(end 0.4318 -0.9525)
			(stroke
				(width 0)
				(type default)
			)
			(fill no)
			(layer "F.Fab")
		)
		(pad "1" smd custom
			(at 0 -0.4445)
			(size 0.1524 0.1524)
			(layers "F.Cu" "F.Mask" "F.Paste")
			(net "HDD_PRSNT_23")
			(options
				(clearance outline)
				(anchor circle)
			)
			(primitives
				(gr_poly
					(pts
						(arc
							(start 0.3048 -0.2032)
							(mid 0.275042 -0.275042)
							(end 0.2032 -0.3048)
						)
						(arc
							(start -0.2032 -0.3048)
							(mid -0.275042 -0.275042)
							(end -0.3048 -0.2032)
						)
						(arc
							(start -0.3048 0.2032)
							(mid -0.275042 0.275042)
							(end -0.2032 0.3048)
						)
						(arc
							(start 0.2032 0.3048)
							(mid 0.275042 0.275042)
							(end 0.3048 0.2032)
						)
					)
					(width 0)
					(fill yes)
				)
			)
		)
		(pad "2" smd custom
			(at 0 0.4445)
			(size 0.1524 0.1524)
			(layers "F.Cu" "F.Mask" "F.Paste")
			(net "GND")
			(options
				(clearance outline)
				(anchor circle)
			)
			(primitives
				(gr_poly
					(pts
						(arc
							(start 0.3048 -0.2032)
							(mid 0.275042 -0.275042)
							(end 0.2032 -0.3048)
						)
						(arc
							(start -0.2032 -0.3048)
							(mid -0.275042 -0.275042)
							(end -0.3048 -0.2032)
						)
						(arc
							(start -0.3048 0.2032)
							(mid -0.275042 0.275042)
							(end -0.2032 0.3048)
						)
						(arc
							(start 0.2032 0.3048)
							(mid 0.275042 0.275042)
							(end 0.3048 0.2032)
						)
					)
					(width 0)
					(fill yes)
				)
			)
		)
	)
)
